# T6G (Grand Teton) — schematic netlist excerpt (pin names and nets, part order shuffled) for the footprints in the layout excerpt that follows; sources: Cadence DE-HDL packaged netlist, KiCad conversion of 04192023_DAF0TMB3IC0_F0TG_MB_C_brd_V02_OCP.brd

C2163  Q_CAP  22UF 4V 20% X6S  pkg C0402  page 68 : A = PVDD18_S5_P0 ; B = GND
C2533  Q_CAP  22UF 4V 20% X6S  pkg C0402  page 70 : A = PVDDCR_SOC_P0 ; B = GND

(kicad_pcb
	(version 20260206)
	(generator "pcbnew")
	(generator_version "10.0")
	(general
		(thickness 1.6)
		(legacy_teardrops no)
	)
	(paper "A4")
	(title_block
		(title "04192023_DAF0TMB3IC0_F0TG_MB_C_brd_V02_OCP.brd")
		(comment 1 "Grand Teton / footprints 8170-8171 of 8354")
	)
	(layers
		(0 "F.Cu" signal "TOP")
		(4 "In1.Cu" signal "GND")
		(6 "In2.Cu" signal "IN1")
		(8 "In3.Cu" signal "GND1")
		(10 "In4.Cu" signal "IN2")
		(12 "In5.Cu" signal "GND2")
		(14 "In6.Cu" signal "IN3")
		(16 "In7.Cu" signal "GND3")
		(18 "In8.Cu" signal "VCC")
		(20 "In9.Cu" signal "VCC1")
		(22 "In10.Cu" signal "GND4")
		(24 "In11.Cu" signal "IN4")
		(26 "In12.Cu" signal "GND5")
		(28 "In13.Cu" signal "IN5")
		(30 "In14.Cu" signal "GND6")
		(32 "In15.Cu" signal "IN6")
		(34 "In16.Cu" signal "GND7")
		(2 "B.Cu" signal "BOTTOM")
		(9 "F.Adhes" user "F.Adhesive")
		(11 "B.Adhes" user "B.Adhesive")
		(13 "F.Paste" user "Package Geometry/Pastemask Top")
		(15 "B.Paste" user "Package Geometry/Pastemask Bottom")
		(5 "F.SilkS" user "Ref Des/Silkscreen Top")
		(7 "B.SilkS" user "Ref Des/Silkscreen Bottom")
		(1 "F.Mask" user "Board Geometry/Soldermask Top")
		(3 "B.Mask" user "Board Geometry/Soldermask Bottom")
		(17 "Dwgs.User" user "User.Drawings")
		(19 "Cmts.User" user "User.Comments")
		(21 "Eco1.User" user "User.Eco1")
		(23 "Eco2.User" user "User.Eco2")
		(25 "Edge.Cuts" user "Board Geometry/Outline")
		(27 "Margin" user)
		(31 "F.CrtYd" user "Package Geometry/Place Bound Top")
		(29 "B.CrtYd" user "Package Geometry/Place Bound Bottom")
		(35 "F.Fab" user "Ref Des/Assembly Top")
		(33 "B.Fab" user "Ref Des/Assembly Bottom")
	)
	(footprint ""
		(layer "B.Cu")
		(at 353.900232 -256.505202 180)
		(property "Reference" "C2163"
			(at 0 0 0)
			(layer "B.SilkS")
			(hide yes)
			(effects
				(font
					(size 1.27 1.27)
				)
				(justify mirror)
			)
		)
		(property "Value" ""
			(at 0 0 0)
			(layer "B.Fab")
			(effects
				(font
					(size 1.27 1.27)
				)
				(justify mirror)
			)
		)
		(duplicate_pad_numbers_are_jumpers no)
		(fp_line
			(start 0.7874 0.4064)
			(end 0.7874 -0.4064)
			(stroke
				(width 0.1524)
				(type default)
			)
			(layer "B.SilkS")
		)
		(fp_line
			(start 0.7874 -0.4064)
			(end -0.7874 -0.4064)
			(stroke
				(width 0.1524)
				(type default)
			)
			(layer "B.SilkS")
		)
		(fp_line
			(start -0.7874 0.4064)
			(end 0.7874 0.4064)
			(stroke
				(width 0.1524)
				(type default)
			)
			(layer "B.SilkS")
		)
		(fp_line
			(start -0.7874 -0.4064)
			(end -0.7874 0.4064)
			(stroke
				(width 0.1524)
				(type default)
			)
			(layer "B.SilkS")
		)
		(fp_line
			(start 0.67945 0.3048)
			(end 0.67945 -0.305054)
			(stroke
				(width 0.1)
				(type default)
			)
			(layer "B.Fab")
		)
		(fp_line
			(start 0.67945 -0.305054)
			(end 0.12065 -0.305054)
			(stroke
				(width 0.1)
				(type default)
			)
			(layer "B.Fab")
		)
		(fp_line
			(start 0.12065 0.3048)
			(end 0.67945 0.3048)
			(stroke
				(width 0.1)
				(type default)
			)
			(layer "B.Fab")
		)
		(fp_line
			(start 0.12065 0.2794)
			(end 0.12065 0.3048)
			(stroke
				(width 0.1)
				(type default)
			)
			(layer "B.Fab")
		)
		(fp_line
			(start 0.12065 -0.2794)
			(end -0.12065 -0.2794)
			(stroke
				(width 0.1)
				(type default)
			)
			(layer "B.Fab")
		)
		(fp_line
			(start 0.12065 -0.305054)
			(end 0.12065 -0.2794)
			(stroke
				(width 0.1)
				(type default)
			)
			(layer "B.Fab")
		)
		(fp_line
			(start -0.120396 0.3048)
			(end -0.120396 0.2794)
			(stroke
				(width 0.1)
				(type default)
			)
			(layer "B.Fab")
		)
		(fp_line
			(start -0.120396 0.2794)
			(end 0.12065 0.2794)
			(stroke
				(width 0.1)
				(type default)
			)
			(layer "B.Fab")
		)
		(fp_line
			(start -0.12065 -0.2794)
			(end -0.12065 -0.3048)
			(stroke
				(width 0.1)
				(type default)
			)
			(layer "B.Fab")
		)
		(fp_line
			(start -0.12065 -0.3048)
			(end -0.67945 -0.3048)
			(stroke
				(width 0.1)
				(type default)
			)
			(layer "B.Fab")
		)
		(fp_line
			(start -0.67945 0.3048)
			(end -0.120396 0.3048)
			(stroke
				(width 0.1)
				(type default)
			)
			(layer "B.Fab")
		)
		(fp_line
			(start -0.67945 -0.3048)
			(end -0.67945 0.3048)
			(stroke
				(width 0.1)
				(type default)
			)
			(layer "B.Fab")
		)
		(pad "1" smd circle
			(at 0.40005 0)
			(size 0 0)
			(layers "B.Cu" "B.Mask" "B.Paste")
			(net "PVDD18_S5_P0")
		)
		(pad "2" smd circle
			(at -0.40005 0)
			(size 0 0)
			(layers "B.Cu" "B.Mask" "B.Paste")
			(net "GND")
		)
	)
	(footprint ""
		(layer "B.Cu")
		(at 351.612454 -262.70331 180)
		(property "Reference" "C2533"
			(at 0 0 0)
			(layer "B.SilkS")
			(hide yes)
			(effects
				(font
					(size 1.27 1.27)
				)
				(justify mirror)
			)
		)
		(property "Value" ""
			(at 0 0 0)
			(layer "B.Fab")
			(effects
				(font
					(size 1.27 1.27)
				)
				(justify mirror)
			)
		)
		(duplicate_pad_numbers_are_jumpers no)
		(fp_line
			(start 0.7874 0.4064)
			(end 0.7874 -0.4064)
			(stroke
				(width 0.1524)
				(type default)
			)
			(layer "B.SilkS")
		)
		(fp_line
			(start 0.7874 -0.4064)
			(end -0.7874 -0.4064)
			(stroke
				(width 0.1524)
				(type default)
			)
			(layer "B.SilkS")
		)
		(fp_line
			(start -0.7874 0.4064)
			(end 0.7874 0.4064)
			(stroke
				(width 0.1524)
				(type default)
			)
			(layer "B.SilkS")
		)
		(fp_line
			(start -0.7874 -0.4064)
			(end -0.7874 0.4064)
			(stroke
				(width 0.1524)
				(type default)
			)
			(layer "B.SilkS")
		)
		(fp_line
			(start 0.67945 0.3048)
			(end 0.67945 -0.305054)
			(stroke
				(width 0.1)
				(type default)
			)
			(layer "B.Fab")
		)
		(fp_line
			(start 0.67945 -0.305054)
			(end 0.12065 -0.305054)
			(stroke
				(width 0.1)
				(type default)
			)
			(layer "B.Fab")
		)
		(fp_line
			(start 0.12065 0.3048)
			(end 0.67945 0.3048)
			(stroke
				(width 0.1)
				(type default)
			)
			(layer "B.Fab")
		)
		(fp_line
			(start 0.12065 0.2794)
			(end 0.12065 0.3048)
			(stroke
				(width 0.1)
				(type default)
			)
			(layer "B.Fab")
		)
		(fp_line
			(start 0.12065 -0.2794)
			(end -0.12065 -0.2794)
			(stroke
				(width 0.1)
				(type default)
			)
			(layer "B.Fab")
		)
		(fp_line
			(start 0.12065 -0.305054)
			(end 0.12065 -0.2794)
			(stroke
				(width 0.1)
				(type default)
			)
			(layer "B.Fab")
		)
		(fp_line
			(start -0.120396 0.3048)
			(end -0.120396 0.2794)
			(stroke
				(width 0.1)
				(type default)
			)
			(layer "B.Fab")
		)
		(fp_line
			(start -0.120396 0.2794)
			(end 0.12065 0.2794)
			(stroke
				(width 0.1)
				(type default)
			)
			(layer "B.Fab")
		)
		(fp_line
			(start -0.12065 -0.2794)
			(end -0.12065 -0.3048)
			(stroke
				(width 0.1)
				(type default)
			)
			(layer "B.Fab")
		)
		(fp_line
			(start -0.12065 -0.3048)
			(end -0.67945 -0.3048)
			(stroke
				(width 0.1)
				(type default)
			)
			(layer "B.Fab")
		)
		(fp_line
			(start -0.67945 0.3048)
			(end -0.120396 0.3048)
			(stroke
				(width 0.1)
				(type default)
			)
			(layer "B.Fab")
		)
		(fp_line
			(start -0.67945 -0.3048)
			(end -0.67945 0.3048)
			(stroke
				(width 0.1)
				(type default)
			)
			(layer "B.Fab")
		)
		(pad "1" smd circle
			(at 0.40005 0)
			(size 0 0)
			(layers "B.Cu" "B.Mask" "B.Paste")
			(net "PVDDCR_SOC_P0")
		)
		(pad "2" smd circle
			(at -0.40005 0)
			(size 0 0)
			(layers "B.Cu" "B.Mask" "B.Paste")
			(net "GND")
		)
	)
)
